# TIMECARD (Time Appliance Project (Time Card)) — schematic netlist excerpt (pin names and nets, part order shuffled) for the footprints in the layout excerpt that follows; sources: Cadence DE-HDL packaged netlist, KiCad conversion of R4006-B0001-02_R01.brd

C66  CAPACITOR  0.1UF 25V 10%  pkg SMC_0402R_H022  page 21 : \1\ = XP5R0V_MAC_USB ; \2\ = SG
L21  FERRITEBEAD  26OHM 25%  pkg SMC_0603R_H030  page 9 : \1\ = XP3R3V_PCIE ; \2\ = XP3R3V

(kicad_pcb
	(version 20260206)
	(generator "pcbnew")
	(generator_version "10.0")
	(general
		(thickness 1.6)
		(legacy_teardrops no)
	)
	(paper "A4")
	(title_block
		(title "timecard-production-celestica-r4006 — R4006-B0001-02_R01.brd")
		(comment 1 "Time Appliance Project (Time Card) / footprints 997-998 of 1113")
	)
	(layers
		(0 "F.Cu" signal "TOP")
		(4 "In1.Cu" signal "L02_GND1")
		(6 "In2.Cu" signal "L03_SIG1")
		(8 "In3.Cu" signal "L04_GND2")
		(10 "In4.Cu" signal "L05_VCC1")
		(12 "In5.Cu" signal "L06_VCC2")
		(14 "In6.Cu" signal "L07_GND3")
		(16 "In7.Cu" signal "L08_SIG2")
		(18 "In8.Cu" signal "L09_GND4")
		(2 "B.Cu" signal "BOTTOM")
		(9 "F.Adhes" user "F.Adhesive")
		(11 "B.Adhes" user "B.Adhesive")
		(13 "F.Paste" user "Package Geometry/Pastemask Top")
		(15 "B.Paste" user "Package Geometry/Pastemask Bottom")
		(5 "F.SilkS" user "Ref Des/Silkscreen Top")
		(7 "B.SilkS" user "Ref Des/Silkscreen Bottom")
		(1 "F.Mask" user "Board Geometry/Soldermask Top")
		(3 "B.Mask" user "Board Geometry/Soldermask Bottom")
		(17 "Dwgs.User" user "User.Drawings")
		(19 "Cmts.User" user "User.Comments")
		(21 "Eco1.User" user "User.Eco1")
		(23 "Eco2.User" user "User.Eco2")
		(25 "Edge.Cuts" user "Board Geometry/Outline")
		(27 "Margin" user)
		(31 "F.CrtYd" user "Package Geometry/Place Bound Top")
		(29 "B.CrtYd" user "Package Geometry/Place Bound Bottom")
		(35 "F.Fab" user "Ref Des/Assembly Top")
		(33 "B.Fab" user "Ref Des/Assembly Bottom")
	)
	(footprint ""
		(layer "B.Cu")
		(at 57.404 -16.51 -90)
		(property "Reference" "L21"
			(at -3.1115 -0.08763 270)
			(unlocked yes)
			(layer "B.SilkS")
			(effects
				(font
					(size 0.7874 0.5842)
					(thickness 0.1524)
				)
				(justify left mirror)
			)
		)
		(property "Value" "VAL*"
			(at 0.9398 3.70967 270)
			(unlocked yes)
			(layer "B.Fab")
			(hide yes)
			(effects
				(font
					(size 0.7874 0.5842)
					(thickness 0.1524)
				)
				(justify left mirror)
			)
		)
		(property "Device Type" "FERRITEBEAD-G191-10101-01,26OHA"
			(at 0.9906 1.22047 270)
			(unlocked yes)
			(layer "B.Fab")
			(hide yes)
			(effects
				(font
					(size 0.7874 0.5842)
					(thickness 0.1524)
				)
				(justify left mirror)
			)
		)
		(property "User Part Number" "PARTNUM*"
			(at 2.54 2.46507 270)
			(unlocked yes)
			(layer "Cmts.User")
			(hide yes)
			(effects
				(font
					(size 0.7874 0.5842)
					(thickness 0.1524)
				)
				(justify left mirror)
			)
		)
		(property "Tolerance" "TOL*"
			(at 0.9906 5.00507 270)
			(unlocked yes)
			(layer "Cmts.User")
			(hide yes)
			(effects
				(font
					(size 0.7874 0.5842)
					(thickness 0.1524)
				)
				(justify left mirror)
			)
		)
		(duplicate_pad_numbers_are_jumpers no)
		(fp_line
			(start -1.3208 0.7112)
			(end 1.3208 0.7112)
			(stroke
				(width 0.1)
				(type default)
			)
			(layer "B.SilkS")
		)
		(fp_line
			(start 1.3208 0.7112)
			(end 1.3208 -0.7112)
			(stroke
				(width 0.1)
				(type default)
			)
			(layer "B.SilkS")
		)
		(fp_line
			(start -1.3208 -0.7112)
			(end -1.3208 0.7112)
			(stroke
				(width 0.1)
				(type default)
			)
			(layer "B.SilkS")
		)
		(fp_line
			(start 1.3208 -0.7112)
			(end -1.3208 -0.7112)
			(stroke
				(width 0.1)
				(type default)
			)
			(layer "B.SilkS")
		)
		(fp_rect
			(start 1.3208 0.7112)
			(end -1.3208 -0.7112)
			(stroke
				(width 0)
				(type default)
			)
			(fill no)
			(layer "B.CrtYd")
		)
		(fp_line
			(start -0.8128 0.4572)
			(end 0.8128 0.4572)
			(stroke
				(width 0.1)
				(type default)
			)
			(layer "B.Fab")
		)
		(fp_line
			(start 0.8128 0.4572)
			(end 0.8128 -0.4572)
			(stroke
				(width 0.1)
				(type default)
			)
			(layer "B.Fab")
		)
		(fp_line
			(start -0.8128 -0.4572)
			(end -0.8128 0.4572)
			(stroke
				(width 0.1)
				(type default)
			)
			(layer "B.Fab")
		)
		(fp_line
			(start 0.8128 -0.4572)
			(end -0.8128 -0.4572)
			(stroke
				(width 0.1)
				(type default)
			)
			(layer "B.Fab")
		)
		(pad "1" smd rect
			(at 0.6858 0 90)
			(size 0.762 0.8636)
			(layers "B.Cu" "B.Mask" "B.Paste")
			(net "XP3R3V_PCIE")
		)
		(pad "2" smd rect
			(at -0.6858 0 90)
			(size 0.762 0.8636)
			(layers "B.Cu" "B.Mask" "B.Paste")
			(net "XP3R3V")
		)
		(zone
			(layer "B.Cu")
			(hatch none 0.5)
			(connect_pads
				(clearance 0)
			)
			(min_thickness 0.25)
			(keepout
				(tracks allowed)
				(vias not_allowed)
				(pads allowed)
				(copperpour not_allowed)
				(footprints allowed)
			)
			(placement
				(enabled no)
				(sheetname "")
			)
			(fill
				(thermal_gap 0.5)
				(thermal_bridge_width 0.5)
				(island_removal_mode 0)
			)
			(polygon
				(pts
					(xy 56.9468 -16.3576) (xy 57.8612 -16.3576) (xy 57.8612 -16.6624) (xy 56.9468 -16.6624)
				)
			)
		)
		(zone
			(layer "B.Cu")
			(hatch none 0.5)
			(connect_pads
				(clearance 0)
			)
			(min_thickness 0.25)
			(keepout
				(tracks not_allowed)
				(vias allowed)
				(pads allowed)
				(copperpour not_allowed)
				(footprints allowed)
			)
			(placement
				(enabled no)
				(sheetname "")
			)
			(fill
				(thermal_gap 0.5)
				(thermal_bridge_width 0.5)
				(island_removal_mode 0)
			)
			(polygon
				(pts
					(xy 56.9468 -16.3576) (xy 57.8612 -16.3576) (xy 57.8612 -16.6624) (xy 56.9468 -16.6624)
				)
			)
		)
	)
	(footprint ""
		(layer "B.Cu")
		(at 76.708 -52.07 180)
		(property "Reference" "C66"
			(at -3.175 0.21463 0)
			(unlocked yes)
			(layer "B.SilkS")
			(effects
				(font
					(size 0.7874 0.5842)
					(thickness 0.1524)
				)
				(justify mirror)
			)
		)
		(property "Value" "VAL*"
			(at -0.0762 2.067306 180)
			(unlocked yes)
			(layer "B.Fab")
			(hide yes)
			(effects
				(font
					(size 0.7874 0.5842)
					(thickness 0.1524)
				)
				(justify mirror)
			)
		)
		(property "Tolerance" "TOL*"
			(at -0.0762 3.032506 180)
			(unlocked yes)
			(layer "Cmts.User")
			(hide yes)
			(effects
				(font
					(size 0.7874 0.5842)
					(thickness 0.1524)
				)
				(justify mirror)
			)
		)
		(property "User Part Number" "PARTNUM*"
			(at -0.1016 4.023106 180)
			(unlocked yes)
			(layer "Cmts.User")
			(hide yes)
			(effects
				(font
					(size 0.7874 0.5842)
					(thickness 0.1524)
				)
				(justify mirror)
			)
		)
		(property "Device Type" "CAPACITOR-G105-0B104-EK,0.1UF,A"
			(at -0.0508 1.127506 180)
			(unlocked yes)
			(layer "B.Fab")
			(hide yes)
			(effects
				(font
					(size 0.7874 0.5842)
					(thickness 0.1524)
				)
				(justify mirror)
			)
		)
		(duplicate_pad_numbers_are_jumpers no)
		(fp_line
			(start 1.143 0.5588)
			(end -1.143 0.5588)
			(stroke
				(width 0.1)
				(type default)
			)
			(layer "B.SilkS")
		)
		(fp_line
			(start 1.143 -0.5588)
			(end 1.143 0.5588)
			(stroke
				(width 0.1)
				(type default)
			)
			(layer "B.SilkS")
		)
		(fp_line
			(start -1.143 0.5588)
			(end -1.143 -0.5588)
			(stroke
				(width 0.1)
				(type default)
			)
			(layer "B.SilkS")
		)
		(fp_line
			(start -1.143 -0.5588)
			(end 1.143 -0.5588)
			(stroke
				(width 0.1)
				(type default)
			)
			(layer "B.SilkS")
		)
		(fp_rect
			(start 1.143 0.5588)
			(end -1.143 -0.5588)
			(stroke
				(width 0)
				(type default)
			)
			(fill no)
			(layer "B.CrtYd")
		)
		(fp_line
			(start 0.508 0.3048)
			(end -0.508 0.3048)
			(stroke
				(width 0.1)
				(type default)
			)
			(layer "B.Fab")
		)
		(fp_line
			(start 0.508 -0.3048)
			(end 0.508 0.3048)
			(stroke
				(width 0.1)
				(type default)
			)
			(layer "B.Fab")
		)
		(fp_line
			(start -0.508 0.3048)
			(end -0.508 -0.3048)
			(stroke
				(width 0.1)
				(type default)
			)
			(layer "B.Fab")
		)
		(fp_line
			(start -0.508 -0.3048)
			(end 0.508 -0.3048)
			(stroke
				(width 0.1)
				(type default)
			)
			(layer "B.Fab")
		)
		(pad "1" smd rect
			(at 0.5334 0)
			(size 0.7112 0.6096)
			(layers "B.Cu" "B.Mask" "B.Paste")
			(net "XP5R0V_MAC_USB")
		)
		(pad "2" smd rect
			(at -0.5334 0)
			(size 0.7112 0.6096)
			(layers "B.Cu" "B.Mask" "B.Paste")
			(net "SG")
		)
		(zone
			(layer "B.Cu")
			(hatch none 0.5)
			(connect_pads
				(clearance 0)
			)
			(min_thickness 0.25)
			(keepout
				(tracks allowed)
				(vias not_allowed)
				(pads allowed)
				(copperpour not_allowed)
				(footprints allowed)
			)
			(placement
				(enabled no)
				(sheetname "")
			)
			(fill
				(thermal_gap 0.5)
				(thermal_bridge_width 0.5)
				(island_removal_mode 0)
			)
			(polygon
				(pts
					(xy 76.6318 -52.3748) (xy 76.6318 -51.7652) (xy 76.7842 -51.7652) (xy 76.7842 -52.3748)
				)
			)
		)
	)
)
